(kicad_pcb
	(version 20260206)
	(generator "pcbnew")
	(generator_version "10.0")
	(general
		(thickness 1.6)
		(legacy_teardrops no)
	)
	(paper "A4")
	(title_block
		(title "v1-chassis-manager — T6M_CM_d_v01_1031_1645.brd")
		(comment 1 "Open CloudServer (Microsoft) / footprints 1372-1376 of 2512")
	)
	(layers
		(0 "F.Cu" signal "TOP")
		(4 "In1.Cu" signal "GND1")
		(6 "In2.Cu" signal "IN1")
		(8 "In3.Cu" signal "VCC1")
		(10 "In4.Cu" signal "VCC2")
		(12 "In5.Cu" signal "GND2")
		(14 "In6.Cu" signal "IN2")
		(16 "In7.Cu" signal "IN3")
		(18 "In8.Cu" signal "GND3")
		(2 "B.Cu" signal "BOTTOM")
		(9 "F.Adhes" user "F.Adhesive")
		(11 "B.Adhes" user "B.Adhesive")
		(13 "F.Paste" user "Package Geometry/Pastemask Top")
		(15 "B.Paste" user "Package Geometry/Pastemask Bottom")
		(5 "F.SilkS" user "Ref Des/Silkscreen Top")
		(7 "B.SilkS" user "Ref Des/Silkscreen Bottom")
		(1 "F.Mask" user "Board Geometry/Soldermask Top")
		(3 "B.Mask" user "Board Geometry/Soldermask Bottom")
		(17 "Dwgs.User" user "User.Drawings")
		(19 "Cmts.User" user "User.Comments")
		(21 "Eco1.User" user "User.Eco1")
		(23 "Eco2.User" user "User.Eco2")
		(25 "Edge.Cuts" user "Board Geometry/Outline")
		(27 "Margin" user)
		(31 "F.CrtYd" user "Package Geometry/Place Bound Top")
		(29 "B.CrtYd" user "Package Geometry/Place Bound Bottom")
		(35 "F.Fab" user "Ref Des/Assembly Top")
		(33 "B.Fab" user "Ref Des/Assembly Bottom")
	)
	(footprint ""
		(layer "F.Cu")
		(at 167.630602 -8.585962 180)
		(property "Reference" "J27"
			(at 6.645402 -3.939032 0)
			(unlocked yes)
			(layer "F.SilkS")
			(effects
				(font
					(size 0.7874 0.5842)
					(thickness 0.1524)
				)
				(justify left)
			)
		)
		(property "Value" ""
			(at 0 0 180)
			(layer "F.Fab")
			(effects
				(font
					(size 1.27 1.27)
				)
			)
		)
		(duplicate_pad_numbers_are_jumpers no)
		(fp_line
			(start 6.599936 2.640076)
			(end -6.599936 2.640076)
			(stroke
				(width 0.1524)
				(type default)
			)
			(layer "F.SilkS")
		)
		(fp_line
			(start 6.599936 -2.640076)
			(end 6.599936 2.640076)
			(stroke
				(width 0.1524)
				(type default)
			)
			(layer "F.SilkS")
		)
		(fp_line
			(start -6.599936 2.640076)
			(end -6.599936 -2.640076)
			(stroke
				(width 0.1524)
				(type default)
			)
			(layer "F.SilkS")
		)
		(fp_line
			(start -6.599936 -2.640076)
			(end 6.599936 -2.640076)
			(stroke
				(width 0.1524)
				(type default)
			)
			(layer "F.SilkS")
		)
		(fp_poly
			(pts
				(xy -4.48818 4.713224) (xy -5.25018 6.618224) (xy -3.72618 6.618224)
			)
			(stroke
				(width 0)
				(type default)
			)
			(fill yes)
			(layer "F.SilkS")
		)
		(fp_poly
			(pts
				(xy -5.969 -2.159) (xy 5.969 -2.159) (xy 5.969 2.159) (xy -5.969 2.159)
			)
			(stroke
				(width 0)
				(type default)
			)
			(fill no)
			(layer "B.CrtYd")
		)
		(fp_poly
			(pts
				(xy -6.599936 2.640076) (xy 6.599936 2.640076) (xy 6.599936 -2.640076) (xy -6.599936 -2.640076)
			)
			(stroke
				(width 0)
				(type default)
			)
			(fill no)
			(layer "F.CrtYd")
		)
		(fp_line
			(start 6.599936 2.640076)
			(end -6.599936 2.640076)
			(stroke
				(width 0.1)
				(type default)
			)
			(layer "F.Fab")
		)
		(fp_line
			(start 6.599936 -2.640076)
			(end 6.599936 2.640076)
			(stroke
				(width 0.1)
				(type default)
			)
			(layer "F.Fab")
		)
		(fp_line
			(start -6.599936 2.640076)
			(end -6.599936 -2.640076)
			(stroke
				(width 0.1)
				(type default)
			)
			(layer "F.Fab")
		)
		(fp_line
			(start -6.599936 -2.640076)
			(end 6.599936 -2.640076)
			(stroke
				(width 0.1)
				(type default)
			)
			(layer "F.Fab")
		)
		(fp_poly
			(pts
				(xy -7.4295 1.27) (xy -9.3345 0.508) (xy -9.3345 2.032)
			)
			(stroke
				(width 0)
				(type default)
			)
			(fill yes)
			(layer "F.Fab")
		)
		(fp_text user "10"
			(at 8.129016 -1.710436 0)
			(unlocked yes)
			(layer "F.SilkS")
			(effects
				(font
					(size 0.7874 0.5842)
					(thickness 0.1524)
				)
				(justify left)
			)
		)
		(fp_text user "9"
			(at 7.730236 2.328164 0)
			(unlocked yes)
			(layer "F.SilkS")
			(effects
				(font
					(size 0.7874 0.5842)
					(thickness 0.1524)
				)
				(justify left)
			)
		)
		(fp_text user "1"
			(at -6.76402 2.261362 0)
			(unlocked yes)
			(layer "F.SilkS")
			(effects
				(font
					(size 0.7874 0.5842)
					(thickness 0.1524)
				)
				(justify left)
			)
		)
		(fp_text user "2"
			(at -6.872732 -1.448562 0)
			(unlocked yes)
			(layer "F.SilkS")
			(effects
				(font
					(size 0.7874 0.5842)
					(thickness 0.1524)
				)
				(justify left)
			)
		)
		(fp_text user "9"
			(at 6.256274 1.067308 0)
			(unlocked yes)
			(layer "B.SilkS")
			(effects
				(font
					(size 0.7874 0.5842)
					(thickness 0.1524)
				)
				(justify left mirror)
			)
		)
		(fp_text user "10"
			(at 6.126734 -1.340866 0)
			(unlocked yes)
			(layer "B.SilkS")
			(effects
				(font
					(size 0.7874 0.5842)
					(thickness 0.1524)
				)
				(justify left mirror)
			)
		)
		(fp_text user "1"
			(at -6.794246 1.360424 0)
			(unlocked yes)
			(layer "B.SilkS")
			(effects
				(font
					(size 0.7874 0.5842)
					(thickness 0.1524)
				)
				(justify left mirror)
			)
		)
		(fp_text user "2"
			(at -6.923786 -0.917956 0)
			(unlocked yes)
			(layer "B.SilkS")
			(effects
				(font
					(size 0.7874 0.5842)
					(thickness 0.1524)
				)
				(justify left mirror)
			)
		)
		(fp_text user "10"
			(at 7.5438 -1.361948 180)
			(unlocked yes)
			(layer "B.Fab")
			(effects
				(font
					(size 0.7874 0.5842)
					(thickness 0.000001)
				)
				(justify left mirror)
			)
		)
		(fp_text user "9"
			(at 7.1501 1.178052 180)
			(unlocked yes)
			(layer "B.Fab")
			(effects
				(font
					(size 0.7874 0.5842)
					(thickness 0.000001)
				)
				(justify left mirror)
			)
		)
		(fp_text user "1"
			(at -6.1849 1.178052 180)
			(unlocked yes)
			(layer "B.Fab")
			(effects
				(font
					(size 0.7874 0.5842)
					(thickness 0.000001)
				)
				(justify left mirror)
			)
		)
		(fp_text user "2"
			(at -6.1849 -1.361948 180)
			(unlocked yes)
			(layer "B.Fab")
			(effects
				(font
					(size 0.7874 0.5842)
					(thickness 0.000001)
				)
				(justify left mirror)
			)
		)
		(fp_text user "9"
			(at 6.9469 1.178052 180)
			(unlocked yes)
			(layer "F.Fab")
			(effects
				(font
					(size 0.7874 0.5842)
					(thickness 0.000001)
				)
				(justify left)
			)
		)
		(fp_text user "10"
			(at 6.5532 -1.361948 180)
			(unlocked yes)
			(layer "F.Fab")
			(effects
				(font
					(size 0.7874 0.5842)
					(thickness 0.000001)
				)
				(justify left)
			)
		)
		(fp_text user "1"
			(at -7.5311 1.178052 180)
			(unlocked yes)
			(layer "F.Fab")
			(effects
				(font
					(size 0.7874 0.5842)
					(thickness 0.000001)
				)
				(justify left)
			)
		)
		(fp_text user "2"
			(at -7.5311 -1.361948 180)
			(unlocked yes)
			(layer "F.Fab")
			(effects
				(font
					(size 0.7874 0.5842)
					(thickness 0.000001)
				)
				(justify left)
			)
		)
		(pad "1" thru_hole rect
			(at -5.08 1.27 270)
			(size 1.6764 1.6764)
			(drill 1.1684)
			(layers "*.Cu" "*.Mask")
			(remove_unused_layers no)
			(net "JTAG_CPLD3_TCK")
			(clearance 0)
			(padstack
				(mode front_inner_back)
				(layer "Inner"
					(shape circle)
					(size 1.6764 1.6764)
					(clearance 0)
				)
				(layer "B.Cu"
					(shape rect)
					(size 1.6764 1.6764)
					(clearance 0)
				)
			)
		)
		(pad "2" thru_hole circle
			(at -5.08 -1.27 270)
			(size 1.6764 1.6764)
			(drill 1.1684)
			(layers "*.Cu" "*.Mask")
			(remove_unused_layers no)
			(net "GND")
			(clearance 0)
		)
		(pad "3" thru_hole circle
			(at -2.54 1.27 270)
			(size 1.6764 1.6764)
			(drill 1.1684)
			(layers "*.Cu" "*.Mask")
			(remove_unused_layers no)
			(net "JTAG_CPLD3_TDO")
			(clearance 0)
		)
		(pad "4" thru_hole circle
			(at -2.54 -1.27 270)
			(size 1.6764 1.6764)
			(drill 1.1684)
			(layers "*.Cu" "*.Mask")
			(remove_unused_layers no)
			(net "P3V3_NODE1")
			(clearance 0)
		)
		(pad "5" thru_hole circle
			(at 0 1.27 270)
			(size 1.6764 1.6764)
			(drill 1.1684)
			(layers "*.Cu" "*.Mask")
			(remove_unused_layers no)
			(net "JTAG_CPLD3_TMS")
			(clearance 0)
		)
		(pad "6" thru_hole circle
			(at 0 -1.27 270)
			(size 1.6764 1.6764)
			(drill 1.1684)
			(layers "*.Cu" "*.Mask")
			(remove_unused_layers no)
			(net "Net_2275")
			(clearance 0)
		)
		(pad "7" thru_hole circle
			(at 2.54 1.27 270)
			(size 1.6764 1.6764)
			(drill 1.1684)
			(layers "*.Cu" "*.Mask")
			(remove_unused_layers no)
			(net "Net_2274")
			(clearance 0)
		)
		(pad "8" thru_hole circle
			(at 2.54 -1.27 270)
			(size 1.6764 1.6764)
			(drill 1.1684)
			(layers "*.Cu" "*.Mask")
			(remove_unused_layers no)
			(net "Net_2273")
			(clearance 0)
		)
		(pad "9" thru_hole circle
			(at 5.08 1.27 270)
			(size 1.6764 1.6764)
			(drill 1.1684)
			(layers "*.Cu" "*.Mask")
			(remove_unused_layers no)
			(net "JTAG_CPLD3_TDI")
			(clearance 0)
		)
		(pad "10" thru_hole circle
			(at 5.08 -1.27 270)
			(size 1.6764 1.6764)
			(drill 1.1684)
			(layers "*.Cu" "*.Mask")
			(remove_unused_layers no)
			(net "GND")
			(clearance 0)
		)
	)
	(footprint ""
		(layer "F.Cu")
		(at 65.464182 -173.527466 180)
		(property "Reference" "U84"
			(at 13.037058 -133.039612 90)
			(unlocked yes)
			(layer "F.SilkS")
			(effects
				(font
					(size 0.7874 0.5842)
					(thickness 0.1524)
				)
				(justify left)
			)
		)
		(property "Value" ""
			(at 0 0 180)
			(layer "F.Fab")
			(effects
				(font
					(size 1.27 1.27)
				)
			)
		)
		(duplicate_pad_numbers_are_jumpers no)
		(fp_line
			(start 1.549908 2.032)
			(end -1.549908 2.032)
			(stroke
				(width 0.1524)
				(type default)
			)
			(layer "F.SilkS")
		)
		(fp_line
			(start 1.549908 -2.032)
			(end 1.549908 2.032)
			(stroke
				(width 0.1524)
				(type default)
			)
			(layer "F.SilkS")
		)
		(fp_line
			(start -1.549908 2.032)
			(end -1.549908 -2.032)
			(stroke
				(width 0.1524)
				(type default)
			)
			(layer "F.SilkS")
		)
		(fp_line
			(start -1.549908 -2.032)
			(end 1.549908 -2.032)
			(stroke
				(width 0.1524)
				(type default)
			)
			(layer "F.SilkS")
		)
		(fp_poly
			(pts
				(xy -2.9464 1.016) (xy -2.9464 1.524) (xy -2.1844 1.27)
			)
			(stroke
				(width 0)
				(type default)
			)
			(fill yes)
			(layer "F.SilkS")
		)
		(fp_poly
			(pts
				(xy -1.549908 0.849884) (xy -1.2319 0.849884) (xy -1.2319 1.9431) (xy -1.1811 1.9431) (xy 1.1811 1.9431)
				(xy 1.2319 1.9431) (xy 1.2319 0.849884) (xy 1.549908 0.849884) (xy 1.549908 -0.849884) (xy 1.2319 -0.849884)
				(xy 1.2319 -1.9431) (xy 1.1811 -1.9431) (xy -1.1811 -1.9431) (xy -1.2319 -1.9431) (xy -1.2319 -0.849884)
				(xy -1.549908 -0.849884)
			)
			(stroke
				(width 0)
				(type default)
			)
			(fill no)
			(layer "F.CrtYd")
		)
		(fp_line
			(start 1.549908 0.849884)
			(end 1.549908 -0.849884)
			(stroke
				(width 0.1)
				(type default)
			)
			(layer "F.Fab")
		)
		(fp_line
			(start 1.549908 -0.849884)
			(end -1.549908 -0.849884)
			(stroke
				(width 0.1)
				(type default)
			)
			(layer "F.Fab")
		)
		(fp_line
			(start -1.549908 0.849884)
			(end 1.549908 0.849884)
			(stroke
				(width 0.1)
				(type default)
			)
			(layer "F.Fab")
		)
		(fp_line
			(start -1.549908 -0.849884)
			(end -1.549908 0.849884)
			(stroke
				(width 0.1)
				(type default)
			)
			(layer "F.Fab")
		)
		(fp_text user "3"
			(at 1.54686 2.678938 0)
			(unlocked yes)
			(layer "F.SilkS")
			(effects
				(font
					(size 0.635 0.4064)
					(thickness 0.1524)
				)
				(justify left)
			)
		)
		(fp_text user "4"
			(at 0.921258 -2.544826 0)
			(unlocked yes)
			(layer "F.SilkS")
			(effects
				(font
					(size 0.635 0.4064)
					(thickness 0.1524)
				)
				(justify left)
			)
		)
		(fp_text user "5"
			(at 0.363982 -2.565908 0)
			(unlocked yes)
			(layer "F.SilkS")
			(effects
				(font
					(size 0.635 0.4064)
					(thickness 0.1524)
				)
				(justify left)
			)
		)
		(fp_text user "1"
			(at -1.401572 2.503932 0)
			(unlocked yes)
			(layer "F.SilkS")
			(effects
				(font
					(size 0.635 0.4064)
					(thickness 0.1524)
				)
				(justify left)
			)
		)
		(pad "1" smd rect
			(at -0.94996 1.225042 180)
			(size 0.4572 1.3208)
			(layers "F.Cu" "F.Mask" "F.Paste")
			(net "Net_1705")
		)
		(pad "2" smd rect
			(at 0 1.225042 180)
			(size 0.4572 1.3208)
			(layers "F.Cu" "F.Mask" "F.Paste")
			(net "PSU1_DC_OK_R_BUF")
		)
		(pad "3" smd rect
			(at 0.94996 1.225042 180)
			(size 0.4572 1.3208)
			(layers "F.Cu" "F.Mask" "F.Paste")
			(net "GND")
		)
		(pad "4" smd rect
			(at 0.94996 -1.225042 180)
			(size 0.4572 1.3208)
			(layers "F.Cu" "F.Mask" "F.Paste")
			(net "PSU1_DC_OK")
		)
		(pad "5" smd rect
			(at -0.94996 -1.225042 180)
			(size 0.4572 1.3208)
			(layers "F.Cu" "F.Mask" "F.Paste")
			(net "P3V3_NODE1")
		)
	)
	(footprint ""
		(layer "F.Cu")
		(at 128.902206 -71.510652 -90)
		(property "Reference" "BT1"
			(at -22.363938 -6.686296 0)
			(unlocked yes)
			(layer "F.SilkS")
			(effects
				(font
					(size 0.7874 0.5842)
					(thickness 0.1524)
				)
				(justify left)
			)
		)
		(property "Value" ""
			(at 0 0 270)
			(layer "F.Fab")
			(effects
				(font
					(size 1.27 1.27)
				)
			)
		)
		(duplicate_pad_numbers_are_jumpers no)
		(fp_line
			(start -1.75006 3.899916)
			(end 1.130046 3.899916)
			(stroke
				(width 0.1524)
				(type default)
			)
			(layer "F.SilkS")
		)
		(fp_line
			(start 1.130046 3.899916)
			(end 1.130046 -3.899916)
			(stroke
				(width 0.1524)
				(type default)
			)
			(layer "F.SilkS")
		)
		(fp_line
			(start 1.130046 -3.899916)
			(end -1.75006 -3.899916)
			(stroke
				(width 0.1524)
				(type default)
			)
			(layer "F.SilkS")
		)
		(fp_circle
			(center -17.629886 8.720074)
			(end -17.629886 7.819898)
			(stroke
				(width 0.1524)
				(type default)
			)
			(fill no)
			(layer "F.SilkS")
		)
		(fp_circle
			(center -12.290044 0)
			(end -12.290044 -11.250168)
			(stroke
				(width 0.1524)
				(type default)
			)
			(fill no)
			(layer "F.SilkS")
		)
		(fp_circle
			(center -4.430014 0)
			(end -4.430014 -0.899922)
			(stroke
				(width 0.1524)
				(type default)
			)
			(fill no)
			(layer "F.SilkS")
		)
		(fp_circle
			(center -17.629886 -8.720074)
			(end -17.629886 -9.619996)
			(stroke
				(width 0.1524)
				(type default)
			)
			(fill no)
			(layer "F.SilkS")
		)
		(fp_poly
			(pts
				(xy 0.8128 0.8128) (xy 0.8128 -0.8128) (xy -0.8128 -0.8128) (xy -0.8128 0.8128)
			)
			(stroke
				(width 0)
				(type default)
			)
			(fill no)
			(layer "B.CrtYd")
		)
		(fp_poly
			(pts
				(arc
					(start -19.99996 -0.762)
					(mid -19.99996 0.762)
					(end -19.99996 -0.762)
				)
			)
			(stroke
				(width 0)
				(type default)
			)
			(fill no)
			(layer "B.CrtYd")
		)
		(fp_poly
			(pts
				(arc
					(start -1.737614 3.899916)
					(mid -23.540072 0)
					(end -1.737614 -3.899916)
				)
				(xy 1.130046 -3.899916) (xy 1.130046 3.899916)
			)
			(stroke
				(width 0)
				(type default)
			)
			(fill no)
			(layer "F.CrtYd")
		)
		(fp_text user "+"
			(at -0.187452 -4.61391 270)
			(unlocked yes)
			(layer "F.SilkS")
			(effects
				(font
					(size 1.6002 1.1938)
					(thickness 0.1524)
				)
				(justify left)
			)
		)
		(pad "1" thru_hole rect
			(at 0 0 270)
			(size 1.6256 1.6256)
			(drill 1.1176)
			(layers "*.Cu" "*.Mask")
			(remove_unused_layers no)
			(net "P3V_COIN_CELL")
			(clearance 0)
			(padstack
				(mode front_inner_back)
				(layer "Inner"
					(shape circle)
					(size 1.6256 1.6256)
					(clearance 0)
				)
				(layer "B.Cu"
					(shape rect)
					(size 1.6256 1.6256)
					(clearance 0)
				)
			)
		)
		(pad "2" thru_hole circle
			(at -19.99996 0 270)
			(size 1.524 1.524)
			(drill 1.016)
			(layers "*.Cu" "*.Mask")
			(remove_unused_layers no)
			(net "GND")
			(clearance 0)
		)
	)
	(footprint ""
		(layer "F.Cu")
		(at 82.02676 -182.411624 -90)
		(property "Reference" "C586"
			(at 1.068324 -1.173226 90)
			(unlocked yes)
			(layer "F.SilkS")
			(effects
				(font
					(size 0.7874 0.5842)
					(thickness 0.1524)
				)
				(justify left)
			)
		)
		(property "Value" ""
			(at 0 0 270)
			(layer "F.Fab")
			(effects
				(font
					(size 1.27 1.27)
				)
			)
		)
		(duplicate_pad_numbers_are_jumpers no)
		(fp_line
			(start -0.7874 0.4064)
			(end -0.7874 -0.4064)
			(stroke
				(width 0.1524)
				(type default)
			)
			(layer "F.SilkS")
		)
		(fp_line
			(start 0.7874 0.4064)
			(end -0.7874 0.4064)
			(stroke
				(width 0.1524)
				(type default)
			)
			(layer "F.SilkS")
		)
		(fp_line
			(start 0 0.381)
			(end 0 -0.381)
			(stroke
				(width 0.1524)
				(type default)
			)
			(layer "F.SilkS")
		)
		(fp_line
			(start -0.7874 -0.4064)
			(end 0.7874 -0.4064)
			(stroke
				(width 0.1524)
				(type default)
			)
			(layer "F.SilkS")
		)
		(fp_line
			(start 0.7874 -0.4064)
			(end 0.7874 0.4064)
			(stroke
				(width 0.1524)
				(type default)
			)
			(layer "F.SilkS")
		)
		(fp_poly
			(pts
				(xy -0.5334 0.254) (xy -0.635 0.254) (xy -0.635 0.2286) (xy -0.635 -0.254) (xy -0.5334 -0.254) (xy -0.5334 -0.2794)
				(xy 0.5334 -0.2794) (xy 0.5334 -0.254) (xy 0.635 -0.254) (xy 0.635 0.254) (xy 0.5334 0.254) (xy 0.5334 0.2794)
				(xy -0.508 0.2794) (xy -0.5334 0.2794)
			)
			(stroke
				(width 0)
				(type default)
			)
			(fill no)
			(layer "F.CrtYd")
		)
		(pad "1" smd rect
			(at 0.40005 0 270)
			(size 0.4572 0.508)
			(layers "F.Cu" "F.Mask" "F.Paste")
			(net "P3V3_NODE1")
		)
		(pad "2" smd rect
			(at -0.40005 0 270)
			(size 0.4572 0.508)
			(layers "F.Cu" "F.Mask" "F.Paste")
			(net "GND")
		)
	)
	(footprint ""
		(layer "F.Cu")
		(at 165.811454 -165.118288)
		(property "Reference" "R575"
			(at 1.22936 0.3937 0)
			(unlocked yes)
			(layer "F.SilkS")
			(effects
				(font
					(size 0.7874 0.5842)
					(thickness 0.1524)
				)
				(justify left)
			)
		)
		(property "Value" ""
			(at 0 0 0)
			(layer "F.Fab")
			(effects
				(font
					(size 1.27 1.27)
				)
			)
		)
		(duplicate_pad_numbers_are_jumpers no)
		(fp_line
			(start -0.7874 -0.4064)
			(end 0.7874 -0.4064)
			(stroke
				(width 0.1524)
				(type default)
			)
			(layer "F.SilkS")
		)
		(fp_line
			(start -0.7874 0.4064)
			(end -0.7874 -0.4064)
			(stroke
				(width 0.1524)
				(type default)
			)
			(layer "F.SilkS")
		)
		(fp_line
			(start 0.7874 -0.4064)
			(end 0.7874 0.4064)
			(stroke
				(width 0.1524)
				(type default)
			)
			(layer "F.SilkS")
		)
		(fp_line
			(start 0.7874 0.4064)
			(end -0.7874 0.4064)
			(stroke
				(width 0.1524)
				(type default)
			)
			(layer "F.SilkS")
		)
		(fp_poly
			(pts
				(xy -0.508 0.2794) (xy -0.508 0.2286) (xy -0.635 0.2286) (xy -0.635 -0.254) (xy -0.5334 -0.254)
				(xy -0.5334 -0.2794) (xy 0.5334 -0.2794) (xy 0.5334 -0.254) (xy 0.635 -0.254) (xy 0.635 0.254) (xy 0.5334 0.254)
				(xy 0.5334 0.2794)
			)
			(stroke
				(width 0)
				(type default)
			)
			(fill no)
			(layer "F.CrtYd")
		)
		(pad "1" smd rect
			(at 0.40005 0)
			(size 0.4572 0.508)
			(layers "F.Cu" "F.Mask" "F.Paste")
			(net "SPI_LAN2_NVM_SK")
		)
		(pad "2" smd rect
			(at -0.40005 0)
			(size 0.4572 0.508)
			(layers "F.Cu" "F.Mask" "F.Paste")
			(net "LAN2_NVM_SK_R")
		)
	)
)
